# S9S_MB_2U (Grand Teton) — schematic parts with pin connectivity, parts 5876–5876 of 6093; source: Cadence DE-HDL packaged netlist (pstxprt.dat, pstxnet.dat, pstchip.dat)

U1  SOCKET4677_AZIF0045P001C01CS  SOCKET4677_AZIF0045-P001C01CS IO  pkg SOCKET4677_82X64-5XA_H466  page 44  (pins 1-327 of 4677)
  A9  DDR0_SB_DQS_DN3  BI  = M_A_CPU1_SB_DQS_DN<3>
  A11  VSS1  POWER  = GND
  A13  VSS2  POWER  = GND
  A15  DDR1_SB_DQS_DN3  BI  = M_B_CPU1_SB_DQS_DN<3>
  A17  VSS3  POWER  = GND
  A19  VSS4  POWER  = GND
  A21  DDR0_SB_DQS_DN2  BI  = M_A_CPU1_SB_DQS_DN<2>
  A23  VSS5  POWER  = GND
  A25  VSS6  POWER  = GND
  A27  DDR0_SB_DQS_DN1  BI  = M_A_CPU1_SB_DQS_DN<1>
  A29  VSS7  POWER  = GND
  A31  VSS8  POWER  = GND
  A33  DDR0_SB_DQS_DN9  BI  = M_A_CPU1_SB_DQS_DN<9>
  A35  VSS9  POWER  = GND
  A37  VSS10  POWER  = GND
  A39  DDR0_SB_CA6  OUT  = M_A_CPU1_SB_CA<6>
  A41  VSS11  POWER  = GND
  A43  DDR01_DRAM_PWR_OK  IN  = PWRGD_DRAMPWRGD_CPU1_AB_LVC1_R
  A50  VSS12  POWER  = GND
  A52  DDR0_SA_CA0  OUT  = M_A_CPU1_SA_CA<0>
  A54  VSS13  POWER  = GND
  A56  VSS14  POWER  = GND
  A58  DDR0_SA_DQS_DN4  BI  = M_A_CPU1_SA_DQS_DN<4>
  A60  VSS15  POWER  = GND
  A62  VSS16  POWER  = GND
  A64  DDR0_SA_DQS_DN3  BI  = M_A_CPU1_SA_DQS_DN<3>
  AA1  UPI0_TX_DN6  OUT  = UPI_CPU1_CPU0_P0P1_DN<6>
  AA3  VCCFA_EHV0  POWER  = PVCCFA_EHV_CPU1
  AA5  UPI0_RX_DN5  IN  = UPI_CPU0_CPU1_P1P0_DN<5>
  AA7  VCCFA_EHV_FIVRA2  POWER  = PVCCFA_EHV_FIVRA_CPU1
  AA9  PE0_RX_DN5  IN  = P5E_CPU1_PE0_RX_DN<5>
  AA11  VCCFA_EHV_FIVRA0  POWER  = PVCCFA_EHV_FIVRA_CPU1
  AA13  PE0_TX_DN4  OUT  = P5E_CPU1_PE0_TX_DN<4>
  AA15  VCCFA_EHV_FIVRA1  POWER  = PVCCFA_EHV_FIVRA_CPU1
  AA17  DDR2_SB_DQ28  BI  = M_C_CPU1_SB_DQ<28>
  AA19  VSS17  POWER  = GND
  AA21  DDR2_SB_DQS_DP7  BI  = M_C_CPU1_SB_DQS_DP<7>
  AA23  VSS18  POWER  = GND
  AA25  VSS19  POWER  = GND
  AA27  DDR1_SB_DQS_DP5  BI  = M_B_CPU1_SB_DQS_DP<5>
  AA29  VSS20  POWER  = GND
  AA31  VSS21  POWER  = GND
  AA33  DDR2_SB_DQS_DP4  BI  = M_C_CPU1_SB_DQS_DP<4>
  AA35  VSS22  POWER  = GND
  AA37  VSS23  POWER  = GND
  AA39  DDR2_SB_PAR  OUT  = M_C_CPU1_SB_PAR
  AA41  VSS24  POWER  = GND
  AA43  VSS25  POWER  = GND
  AA45  DDR1_CLK_DP1  OUT  = M_B_CPU1_CLK_DP<1>
  AA48  VSS26  POWER  = GND
  AA50  VSS27  POWER  = GND
  AA52  DDR2_SA_CA1  OUT  = M_C_CPU1_SA_CA<1>
  AA54  VSS28  POWER  = GND
  AA56  VSS29  POWER  = GND
  AA58  DDR1_SA_DQS_DN8  BI  = M_B_CPU1_SA_DQS_DN<8>
  AA60  VSS30  POWER  = GND
  AA62  VSS31  POWER  = GND
  AA64  DDR2_SA_DQS_DN7  BI  = M_C_CPU1_SA_DQS_DN<7>
  AA66  VSS32  POWER  = GND
  AA68  VSS33  POWER  = GND
  AA70  DDR1_SA_DQS_DN6  BI  = M_B_CPU1_SA_DQS_DN<6>
  AA72  VSS34  POWER  = GND
  AA74  VSS35  POWER  = GND
  AA76  DDR2_SA_DQS_DP5  BI  = M_C_CPU1_SA_DQS_DP<5>
  AA78  VSS36  POWER  = GND
  AA80  VSS37  POWER  = GND
  AA82  VSS38  POWER  = GND
  AA84  VSS39  POWER  = GND
  AA86  PE4_TX_DN5  OUT  = P5E_CPU1_PE4_TX_DN<5>
  AA88  VSS40  POWER  = GND
  AA90  PE4_RX_DP5  IN  = P5E_CPU1_PE4_RX_DP<5>
  AB2  UPI0_TX_DP6  OUT  = UPI_CPU1_CPU0_P0P1_DP<6>
  AB4  VSS50  POWER  = GND
  AB6  UPI0_RX_DN6  IN  = UPI_CPU0_CPU1_P1P0_DN<6>
  AB8  VSS65  POWER  = GND
  AB10  PE0_RX_DN6  IN  = P5E_CPU1_PE0_RX_DN<6>
  AB12  VSS41  POWER  = GND
  AB14  PE0_TX_DN5  OUT  = P5E_CPU1_PE0_TX_DN<5>
  AB16  VSS42  POWER  = GND
  AB18  DDR2_SB_DQS_DN3  BI  = M_C_CPU1_SB_DQS_DN<3>
  AB20  VSS43  POWER  = GND
  AB22  VSS44  POWER  = GND
  AB24  DDR3_SB_DQS_DN2  BI  = M_D_CPU1_SB_DQS_DN<2>
  AB26  VSS45  POWER  = GND
  AB28  VSS46  POWER  = GND
  AB30  DDR2_SB_DQS_DN1  BI  = M_C_CPU1_SB_DQS_DN<1>
  AB32  VSS47  POWER  = GND
  AB34  VSS48  POWER  = GND
  AB36  DDR2_SB_DQS_DN0  BI  = M_C_CPU1_SB_DQS_DN<0>
  AB38  VSS49  POWER  = GND
  AB40  VSS51  POWER  = GND
  AB42  DDR3_SB_CA6  OUT  = M_D_CPU1_SB_CA<6>
  AB44  VSS52  POWER  = GND
  AB47  VSS53  POWER  = GND
  AB49  DDR2_CLK_DN0  OUT  = M_C_CPU1_CLK_DN<0>
  AB51  VSS54  POWER  = GND
  AB53  VSS55  POWER  = GND
  AB55  DDR2_SA_DQS_DP4  BI  = M_C_CPU1_SA_DQS_DP<4>
  AB57  VSS56  POWER  = GND
  AB59  VSS57  POWER  = GND
  AB61  DDR2_SA_DQS_DN3  BI  = M_C_CPU1_SA_DQS_DN<3>
  AB63  VSS58  POWER  = GND
  AB65  VSS59  POWER  = GND
  AB67  DDR2_SA_DQS_DN1  BI  = M_C_CPU1_SA_DQS_DN<1>
  AB69  VSS60  POWER  = GND
  AB71  VSS61  POWER  = GND
  AB73  DDR3_SA_DQS_DN0  BI  = M_D_CPU1_SA_DQS_DN<0>
  AB75  VSS62  POWER  = GND
  AB77  VSS63  POWER  = GND
  AB79  VSS64  POWER  = GND
  AB81  VSS66  POWER  = GND
  AB83  VSS67  POWER  = GND
  AB85  PE4_TX_DP5  OUT  = P5E_CPU1_PE4_TX_DP<5>
  AB87  VSS68  POWER  = GND
  AB89  PE4_RX_DN5  IN  = P5E_CPU1_PE4_RX_DN<5>
  AB91  VSS69  POWER  = GND
  AC1  VSS70  POWER  = GND
  AC3  UPI0_TX_DP7  OUT  = UPI_CPU1_CPU0_P0P1_DP<7>
  AC5  VSS77  POWER  = GND
  AC7  UPI0_RX_DP6  IN  = UPI_CPU0_CPU1_P1P0_DP<6>
  AC9  VSS85  POWER  = GND
  AC11  PE0_RX_DP6  IN  = P5E_CPU1_PE0_RX_DP<6>
  AC13  VSS71  POWER  = GND
  AC15  PE0_TX_DP5  OUT  = P5E_CPU1_PE0_TX_DP<5>
  AC17  DDR2_SB_DQ30  BI  = M_C_CPU1_SB_DQ<30>
  AC19  DDR2_SB_DQ25  BI  = M_C_CPU1_SB_DQ<25>
  AC21  VSS72  POWER  = GND
  AC23  DDR3_SB_DQ20  BI  = M_D_CPU1_SB_DQ<20>
  AC25  DDR3_SB_DQ17  BI  = M_D_CPU1_SB_DQ<17>
  AC27  VSS73  POWER  = GND
  AC29  DDR2_SB_DQ12  BI  = M_C_CPU1_SB_DQ<12>
  AC31  DDR2_SB_DQ9  BI  = M_C_CPU1_SB_DQ<9>
  AC33  VSS74  POWER  = GND
  AC35  DDR2_SB_DQ4  BI  = M_C_CPU1_SB_DQ<4>
  AC37  DDR2_SB_DQ1  BI  = M_C_CPU1_SB_DQ<1>
  AC39  VSS75  POWER  = GND
  AC41  DDR3_SB_CS_N0  OUT  = M_D_CPU1_SB_CS_N<0>
  AC43  DDR3_SB_CA4  OUT  = M_D_CPU1_SB_CA<4>
  AC45  VSS76  POWER  = GND
  AC48  DDR2_A_RSP0  IN  = M_C_CPU1_SA_RSP<0>
  AC50  DDR3_A_RSP1  IN  = M_D_CPU1_SA_RSP<1>
  AC52  VSS78  POWER  = GND
  AC54  DDR2_SA_ECC4  BI  = M_C_CPU1_SA_CB<4>
  AC56  DDR2_SA_ECC1  BI  = M_C_CPU1_SA_CB<1>
  AC58  VSS79  POWER  = GND
  AC60  DDR2_SA_DQ28  BI  = M_C_CPU1_SA_DQ<28>
  AC62  DDR2_SA_DQ25  BI  = M_C_CPU1_SA_DQ<25>
  AC64  VSS80  POWER  = GND
  AC66  DDR2_SA_DQ12  BI  = M_C_CPU1_SA_DQ<12>
  AC68  DDR2_SA_DQ9  BI  = M_C_CPU1_SA_DQ<9>
  AC70  VSS81  POWER  = GND
  AC72  DDR3_SA_DQ4  BI  = M_D_CPU1_SA_DQ<4>
  AC74  DDR3_SA_DQ1  BI  = M_D_CPU1_SA_DQ<1>
  AC76  VSS82  POWER  = GND
  AC78  RSVD0  BI  = NC_CPU1_HBM2_VIEWDIG0
  AC80  UPI2_RX_DN6  IN  = UPI_CPU0_CPU1_P2P2_DN<6>
  AC82  UPI2_RX_DP7  IN  = UPI_CPU0_CPU1_P2P2_DP<7>
  AC84  VSS83  POWER  = GND
  AC86  PE4_TX_DN6  OUT  = P5E_CPU1_PE4_TX_DN<6>
  AC88  VSS84  POWER  = GND
  AC90  PE4_RX_DP6  IN  = P5E_CPU1_PE4_RX_DP<6>
  AD2  UPI0_TX_DN7  OUT  = UPI_CPU1_CPU0_P0P1_DN<7>
  AD4  VSS88  POWER  = GND
  AD6  UPI0_RX_DP7  IN  = UPI_CPU0_CPU1_P1P0_DP<7>
  AD8  VSS91  POWER  = GND
  AD10  PE0_RX_DP7  IN  = P5E_CPU1_PE0_RX_DP<7>
  AD12  VSS86  POWER  = GND
  AD14  PE0_TX_DP6  OUT  = P5E_CPU1_PE0_TX_DP<6>
  AD16  VSS87  POWER  = GND
  AD18  DDR2_SB_DQS_DP3  BI  = M_C_CPU1_SB_DQS_DP<3>
  AD20  DDR2_SB_DQ24  BI  = M_C_CPU1_SB_DQ<24>
  AD22  DDR3_SB_DQ21  BI  = M_D_CPU1_SB_DQ<21>
  AD24  DDR3_SB_DQS_DP2  BI  = M_D_CPU1_SB_DQS_DP<2>
  AD26  DDR3_SB_DQ16  BI  = M_D_CPU1_SB_DQ<16>
  AD28  DDR2_SB_DQ13  BI  = M_C_CPU1_SB_DQ<13>
  AD30  DDR2_SB_DQS_DP1  BI  = M_C_CPU1_SB_DQS_DP<1>
  AD32  DDR2_SB_DQ8  BI  = M_C_CPU1_SB_DQ<8>
  AD34  DDR2_SB_DQ5  BI  = M_C_CPU1_SB_DQ<5>
  AD36  DDR2_SB_DQS_DP0  BI  = M_C_CPU1_SB_DQS_DP<0>
  AD38  DDR2_SB_DQ0  BI  = M_C_CPU1_SB_DQ<0>
  AD40  DDR3_SB_CS_N3  OUT  = M_D_CPU1_SB_CS_N<3>
  AD42  VSS89  POWER  = GND
  AD44  DDR3_SB_CA2  OUT  = M_D_CPU1_SB_CA<2>
  AD47  DDR2_A_RSP1  IN  = M_C_CPU1_SA_RSP<1>
  AD49  DDR2_CLK_DP0  OUT  = M_C_CPU1_CLK_DP<0>
  AD51  DDR3_A_RSP0  IN  = M_D_CPU1_SA_RSP<0>
  AD53  DDR2_SA_ECC5  BI  = M_C_CPU1_SA_CB<5>
  AD55  DDR2_SA_DQS_DN4  BI  = M_C_CPU1_SA_DQS_DN<4>
  AD57  DDR2_SA_ECC0  BI  = M_C_CPU1_SA_CB<0>
  AD59  DDR2_SA_DQ29  BI  = M_C_CPU1_SA_DQ<29>
  AD61  DDR2_SA_DQS_DP3  BI  = M_C_CPU1_SA_DQS_DP<3>
  AD63  DDR2_SA_DQ24  BI  = M_C_CPU1_SA_DQ<24>
  AD65  DDR2_SA_DQ13  BI  = M_C_CPU1_SA_DQ<13>
  AD67  DDR2_SA_DQS_DP1  BI  = M_C_CPU1_SA_DQS_DP<1>
  AD69  DDR2_SA_DQ8  BI  = M_C_CPU1_SA_DQ<8>
  AD71  DDR3_SA_DQ5  BI  = M_D_CPU1_SA_DQ<5>
  AD73  DDR3_SA_DQS_DP0  BI  = M_D_CPU1_SA_DQS_DP<0>
  AD75  DDR3_SA_DQ0  BI  = M_D_CPU1_SA_DQ<0>
  AD77  RSVD1  BI  = NC_CPU1_HBM2_VIEWDIG1
  AD79  VSS90  POWER  = GND
  AD81  UPI2_RX_DN7  IN  = UPI_CPU0_CPU1_P2P2_DN<7>
  AD83  VSS92  POWER  = GND
  AD85  VCCFA_EHV_FIVRA3  POWER  = PVCCFA_EHV_FIVRA_CPU1
  AD87  PE4_TX_DP6  OUT  = P5E_CPU1_PE4_TX_DP<6>
  AD89  VCCFA_EHV_FIVRA4  POWER  = PVCCFA_EHV_FIVRA_CPU1
  AD91  PE4_RX_DN6  IN  = P5E_CPU1_PE4_RX_DN<6>
  AE1  UPI0_TX_DP8  OUT  = UPI_CPU1_CPU0_P0P1_DP<8>
  AE3  VCCFA_EHV1  POWER  = PVCCFA_EHV_CPU1
  AE5  UPI0_RX_DN7  IN  = UPI_CPU0_CPU1_P1P0_DN<7>
  AE7  VCCFA_EHV_FIVRA7  POWER  = PVCCFA_EHV_FIVRA_CPU1
  AE9  PE0_RX_DN7  IN  = P5E_CPU1_PE0_RX_DN<7>
  AE11  VCCFA_EHV_FIVRA5  POWER  = PVCCFA_EHV_FIVRA_CPU1
  AE13  PE0_TX_DN6  OUT  = P5E_CPU1_PE0_TX_DN<6>
  AE15  VCCFA_EHV_FIVRA6  POWER  = PVCCFA_EHV_FIVRA_CPU1
  AE17  VSS93  POWER  = GND
  AE19  VSS94  POWER  = GND
  AE21  VSS95  POWER  = GND
  AE23  VSS96  POWER  = GND
  AE25  VSS97  POWER  = GND
  AE27  VSS98  POWER  = GND
  AE29  VSS99  POWER  = GND
  AE31  VSS100  POWER  = GND
  AE33  VSS101  POWER  = GND
  AE35  VSS102  POWER  = GND
  AE37  VSS103  POWER  = GND
  AE39  VSS104  POWER  = GND
  AE41  VSS105  POWER  = GND
  AE43  VSS106  POWER  = GND
  AE45  VSS107  POWER  = GND
  AE48  VSS108  POWER  = GND
  AE50  VSS109  POWER  = GND
  AE52  VSS110  POWER  = GND
  AE54  VSS111  POWER  = GND
  AE56  VSS112  POWER  = GND
  AE58  VSS113  POWER  = GND
  AE60  VSS114  POWER  = GND
  AE62  VSS115  POWER  = GND
  AE64  VSS116  POWER  = GND
  AE66  VSS117  POWER  = GND
  AE68  VSS118  POWER  = GND
  AE70  VSS119  POWER  = GND
  AE72  VSS120  POWER  = GND
  AE74  VSS121  POWER  = GND
  AE76  VSS122  POWER  = GND
  AE78  VSS123  POWER  = GND
  AE80  UPI2_RX_DP6  IN  = UPI_CPU0_CPU1_P2P2_DP<6>
  AE82  UPI2_RX_DN9  IN  = UPI_CPU0_CPU1_P2P2_DN<9>
  AE84  VSS124  POWER  = GND
  AE86  PE4_TX_DN7  OUT  = P5E_CPU1_PE4_TX_DN<7>
  AE88  VSS125  POWER  = GND
  AE90  PE4_RX_DP7  IN  = P5E_CPU1_PE4_RX_DP<7>
  AF2  UPI0_TX_DN8  OUT  = UPI_CPU1_CPU0_P0P1_DN<8>
  AF4  VSS128  POWER  = GND
  AF6  UPI0_RX_DN8  IN  = UPI_CPU0_CPU1_P1P0_DN<8>
  AF8  VSS130  POWER  = GND
  AF10  PE0_RX_DN8  IN  = P5E_CPU1_PE0_RX_DN<8>
  AF12  VSS126  POWER  = GND
  AF14  PE0_TX_DN7  OUT  = P5E_CPU1_PE0_TX_DN<7>
  AF16  VSS127  POWER  = GND
  AF18  DDR2_SB_DQS_DN8  BI  = M_C_CPU1_SB_DQS_DN<8>
  AF20  DDR2_SB_DQ26  BI  = M_C_CPU1_SB_DQ<26>
  AF22  DDR3_SB_DQ23  BI  = M_D_CPU1_SB_DQ<23>
  AF24  DDR3_SB_DQS_DN7  BI  = M_D_CPU1_SB_DQS_DN<7>
  AF26  DDR3_SB_DQ18  BI  = M_D_CPU1_SB_DQ<18>
  AF28  DDR2_SB_DQ15  BI  = M_C_CPU1_SB_DQ<15>
  AF30  DDR2_SB_DQS_DN6  BI  = M_C_CPU1_SB_DQS_DN<6>
  AF32  DDR2_SB_DQ10  BI  = M_C_CPU1_SB_DQ<10>
  AF34  DDR2_SB_DQ7  BI  = M_C_CPU1_SB_DQ<7>
  AF36  DDR2_SB_DQS_DN5  BI  = M_C_CPU1_SB_DQS_DN<5>
  AF38  DDR2_SB_DQ2  BI  = M_C_CPU1_SB_DQ<2>
  AF40  DDR3_SB_CS_N2  OUT  = M_D_CPU1_SB_CS_N<2>
  AF42  VSS129  POWER  = GND
  AF44  DDR3_SB_CA3  OUT  = M_D_CPU1_SB_CA<3>
  AF47  DDR2_B_RSP1  IN  = M_C_CPU1_SB_RSP<1>
  AF49  DDR2_CLK_DN1  OUT  = M_C_CPU1_CLK_DN<1>
  AF51  DDR3_B_RSP0  IN  = M_D_CPU1_SB_RSP<0>
  AF53  DDR2_SA_ECC7  BI  = M_C_CPU1_SA_CB<7>
  AF55  DDR2_SA_DQS_DP9  BI  = M_C_CPU1_SA_DQS_DP<9>
  AF57  DDR2_SA_ECC2  BI  = M_C_CPU1_SA_CB<2>
  AF59  DDR2_SA_DQ31  BI  = M_C_CPU1_SA_DQ<31>
  AF61  DDR2_SA_DQS_DN8  BI  = M_C_CPU1_SA_DQS_DN<8>
  AF63  DDR2_SA_DQ26  BI  = M_C_CPU1_SA_DQ<26>
  AF65  DDR2_SA_DQ15  BI  = M_C_CPU1_SA_DQ<15>
  AF67  DDR2_SA_DQS_DP6  BI  = M_C_CPU1_SA_DQS_DP<6>
  AF69  DDR2_SA_DQ10  BI  = M_C_CPU1_SA_DQ<10>
  AF71  DDR3_SA_DQ7  BI  = M_D_CPU1_SA_DQ<7>
  AF73  DDR3_SA_DQS_DP5  BI  = M_D_CPU1_SA_DQS_DP<5>
  AF75  DDR3_SA_DQ2  BI  = M_D_CPU1_SA_DQ<2>
  AF77  VCCFA_EHV_FIVRA8  POWER  = PVCCFA_EHV_FIVRA_CPU1
  AF79  UPI2_RX_DN8  IN  = UPI_CPU0_CPU1_P2P2_DN<8>
  AF81  VSS131  POWER  = GND
  AF83  UPI2_RX_DP9  IN  = UPI_CPU0_CPU1_P2P2_DP<9>
  AF85  PE4_TX_DP7  OUT  = P5E_CPU1_PE4_TX_DP<7>
  AF87  VSS132  POWER  = GND
  AF89  PE4_RX_DN7  IN  = P5E_CPU1_PE4_RX_DN<7>
  AF91  VSS133  POWER  = GND
  AG1  VSS134  POWER  = GND
  AG3  UPI0_TX_DP9  OUT  = UPI_CPU1_CPU0_P0P1_DP<9>
  AG5  VSS141  POWER  = GND
  AG7  UPI0_RX_DP8  IN  = UPI_CPU0_CPU1_P1P0_DP<8>
  AG9  VSS149  POWER  = GND
  AG11  PE0_RX_DP8  IN  = P5E_CPU1_PE0_RX_DP<8>
  AG13  VSS135  POWER  = GND
  AG15  PE0_TX_DP7  OUT  = P5E_CPU1_PE0_TX_DP<7>
  AG17  DDR2_SB_DQ29  BI  = M_C_CPU1_SB_DQ<29>
  AG19  DDR2_SB_DQ27  BI  = M_C_CPU1_SB_DQ<27>
  AG21  VSS136  POWER  = GND
  AG23  DDR3_SB_DQ22  BI  = M_D_CPU1_SB_DQ<22>
  AG25  DDR3_SB_DQ19  BI  = M_D_CPU1_SB_DQ<19>
  AG27  VSS137  POWER  = GND
  AG29  DDR2_SB_DQ14  BI  = M_C_CPU1_SB_DQ<14>
  AG31  DDR2_SB_DQ11  BI  = M_C_CPU1_SB_DQ<11>
  AG33  VSS138  POWER  = GND
  AG35  DDR2_SB_DQ6  BI  = M_C_CPU1_SB_DQ<6>
  AG37  DDR2_SB_DQ3  BI  = M_C_CPU1_SB_DQ<3>
  AG39  VSS139  POWER  = GND
  AG41  DDR3_SB_CS_N1  OUT  = M_D_CPU1_SB_CS_N<1>
  AG43  DDR3_SB_CA5  OUT  = M_D_CPU1_SB_CA<5>
  AG45  VSS140  POWER  = GND
  AG48  DDR2_B_RSP0  IN  = M_C_CPU1_SB_RSP<0>
  AG50  DDR3_B_RSP1  IN  = M_D_CPU1_SB_RSP<1>
  AG52  VSS142  POWER  = GND
  AG54  DDR2_SA_ECC6  BI  = M_C_CPU1_SA_CB<6>
  AG56  DDR2_SA_ECC3  BI  = M_C_CPU1_SA_CB<3>
  AG58  VSS143  POWER  = GND
  AG60  DDR2_SA_DQ30  BI  = M_C_CPU1_SA_DQ<30>
  AG62  DDR2_SA_DQ27  BI  = M_C_CPU1_SA_DQ<27>
